# S9S_MB_2U (Grand Teton) — schematic netlist excerpt (pin names and nets, part order shuffled) for the footprints in the layout excerpt that follows; sources: Cadence DE-HDL packaged netlist, KiCad conversion of 03242023_DA0F0TMBIJ0_F0T_Motherboard_J_brd_V01_OCP.brd

R4040  Q_RES  1K 1% CHIP  pkg 0402LF  page 225 : A = P0V62_CPU1_RST_DDR_VREF ; B = GND
R269  Q_RES  33.2 1% CHIP  pkg 0402LF  page 223 : A = FM_ADR_MODE1 ; B = FM_ADR_MODE1_R

(kicad_pcb
	(version 20260206)
	(generator "pcbnew")
	(generator_version "10.0")
	(general
		(thickness 1.6)
		(legacy_teardrops no)
	)
	(paper "A4")
	(title_block
		(title "03242023_DA0F0TMBIJ0_F0T_Motherboard_J_brd_V01_OCP.brd")
		(comment 1 "Grand Teton / footprints 1128-1129 of 6105")
	)
	(layers
		(0 "F.Cu" signal "TOP")
		(4 "In1.Cu" signal "GND")
		(6 "In2.Cu" signal "IN1")
		(8 "In3.Cu" signal "GND1")
		(10 "In4.Cu" signal "IN2")
		(12 "In5.Cu" signal "GND2")
		(14 "In6.Cu" signal "IN3")
		(16 "In7.Cu" signal "GND3")
		(18 "In8.Cu" signal "VCC")
		(20 "In9.Cu" signal "VCC1")
		(22 "In10.Cu" signal "GND4")
		(24 "In11.Cu" signal "IN4")
		(26 "In12.Cu" signal "GND5")
		(28 "In13.Cu" signal "IN5")
		(30 "In14.Cu" signal "GND6")
		(32 "In15.Cu" signal "IN6")
		(34 "In16.Cu" signal "GND7")
		(2 "B.Cu" signal "BOTTOM")
		(9 "F.Adhes" user "F.Adhesive")
		(11 "B.Adhes" user "B.Adhesive")
		(13 "F.Paste" user "Package Geometry/Pastemask Top")
		(15 "B.Paste" user "Package Geometry/Pastemask Bottom")
		(5 "F.SilkS" user "Ref Des/Silkscreen Top")
		(7 "B.SilkS" user "Ref Des/Silkscreen Bottom")
		(1 "F.Mask" user "Board Geometry/Soldermask Top")
		(3 "B.Mask" user "Board Geometry/Soldermask Bottom")
		(17 "Dwgs.User" user "User.Drawings")
		(19 "Cmts.User" user "User.Comments")
		(21 "Eco1.User" user "User.Eco1")
		(23 "Eco2.User" user "User.Eco2")
		(25 "Edge.Cuts" user "Board Geometry/Outline")
		(27 "Margin" user)
		(31 "F.CrtYd" user "Package Geometry/Place Bound Top")
		(29 "B.CrtYd" user "Package Geometry/Place Bound Bottom")
		(35 "F.Fab" user "Ref Des/Assembly Top")
		(33 "B.Fab" user "Ref Des/Assembly Bottom")
	)
	(footprint ""
		(layer "F.Cu")
		(at 193.60388 -102.415848 180)
		(property "Reference" "R269"
			(at 0 0 180)
			(layer "F.SilkS")
			(hide yes)
			(effects
				(font
					(size 1.27 1.27)
				)
			)
		)
		(property "Value" ""
			(at 0 0 180)
			(layer "F.Fab")
			(effects
				(font
					(size 1.27 1.27)
				)
			)
		)
		(duplicate_pad_numbers_are_jumpers no)
		(fp_line
			(start 0.7874 0.4064)
			(end -0.7874 0.4064)
			(stroke
				(width 0.1524)
				(type default)
			)
			(layer "F.SilkS")
		)
		(fp_line
			(start 0.7874 -0.4064)
			(end 0.7874 0.4064)
			(stroke
				(width 0.1524)
				(type default)
			)
			(layer "F.SilkS")
		)
		(fp_line
			(start -0.7874 0.4064)
			(end -0.7874 -0.4064)
			(stroke
				(width 0.1524)
				(type default)
			)
			(layer "F.SilkS")
		)
		(fp_line
			(start -0.7874 -0.4064)
			(end 0.7874 -0.4064)
			(stroke
				(width 0.1524)
				(type default)
			)
			(layer "F.SilkS")
		)
		(fp_line
			(start 0.67945 0.3048)
			(end 0.120396 0.3048)
			(stroke
				(width 0.1)
				(type default)
			)
			(layer "F.Fab")
		)
		(fp_line
			(start 0.67945 -0.3048)
			(end 0.67945 0.3048)
			(stroke
				(width 0.1)
				(type default)
			)
			(layer "F.Fab")
		)
		(fp_line
			(start 0.12065 -0.2794)
			(end 0.12065 -0.3048)
			(stroke
				(width 0.1)
				(type default)
			)
			(layer "F.Fab")
		)
		(fp_line
			(start 0.12065 -0.3048)
			(end 0.67945 -0.3048)
			(stroke
				(width 0.1)
				(type default)
			)
			(layer "F.Fab")
		)
		(fp_line
			(start 0.120396 0.3048)
			(end 0.120396 0.2794)
			(stroke
				(width 0.1)
				(type default)
			)
			(layer "F.Fab")
		)
		(fp_line
			(start 0.120396 0.2794)
			(end -0.12065 0.2794)
			(stroke
				(width 0.1)
				(type default)
			)
			(layer "F.Fab")
		)
		(fp_line
			(start -0.12065 0.3048)
			(end -0.67945 0.3048)
			(stroke
				(width 0.1)
				(type default)
			)
			(layer "F.Fab")
		)
		(fp_line
			(start -0.12065 0.2794)
			(end -0.12065 0.3048)
			(stroke
				(width 0.1)
				(type default)
			)
			(layer "F.Fab")
		)
		(fp_line
			(start -0.12065 -0.2794)
			(end 0.12065 -0.2794)
			(stroke
				(width 0.1)
				(type default)
			)
			(layer "F.Fab")
		)
		(fp_line
			(start -0.12065 -0.305054)
			(end -0.12065 -0.2794)
			(stroke
				(width 0.1)
				(type default)
			)
			(layer "F.Fab")
		)
		(fp_line
			(start -0.67945 0.3048)
			(end -0.67945 -0.305054)
			(stroke
				(width 0.1)
				(type default)
			)
			(layer "F.Fab")
		)
		(fp_line
			(start -0.67945 -0.305054)
			(end -0.12065 -0.305054)
			(stroke
				(width 0.1)
				(type default)
			)
			(layer "F.Fab")
		)
		(pad "1" smd circle
			(at -0.40005 0 180)
			(size 0 0)
			(layers "F.Cu" "F.Mask" "F.Paste")
			(net "FM_ADR_MODE1")
		)
		(pad "2" smd circle
			(at 0.40005 0 180)
			(size 0 0)
			(layers "F.Cu" "F.Mask" "F.Paste")
			(net "FM_ADR_MODE1_R")
		)
	)
	(footprint ""
		(layer "F.Cu")
		(at 122.978926 -122.096784 90)
		(property "Reference" "R4040"
			(at 0 0 90)
			(layer "F.SilkS")
			(hide yes)
			(effects
				(font
					(size 1.27 1.27)
				)
			)
		)
		(property "Value" ""
			(at 0 0 90)
			(layer "F.Fab")
			(effects
				(font
					(size 1.27 1.27)
				)
			)
		)
		(duplicate_pad_numbers_are_jumpers no)
		(fp_line
			(start 0.7874 -0.4064)
			(end 0.7874 0.4064)
			(stroke
				(width 0.1524)
				(type default)
			)
			(layer "F.SilkS")
		)
		(fp_line
			(start -0.7874 -0.4064)
			(end 0.7874 -0.4064)
			(stroke
				(width 0.1524)
				(type default)
			)
			(layer "F.SilkS")
		)
		(fp_line
			(start 0.7874 0.4064)
			(end -0.7874 0.4064)
			(stroke
				(width 0.1524)
				(type default)
			)
			(layer "F.SilkS")
		)
		(fp_line
			(start -0.7874 0.4064)
			(end -0.7874 -0.4064)
			(stroke
				(width 0.1524)
				(type default)
			)
			(layer "F.SilkS")
		)
		(fp_line
			(start -0.12065 -0.305054)
			(end -0.12065 -0.2794)
			(stroke
				(width 0.1)
				(type default)
			)
			(layer "F.Fab")
		)
		(fp_line
			(start -0.67945 -0.305054)
			(end -0.12065 -0.305054)
			(stroke
				(width 0.1)
				(type default)
			)
			(layer "F.Fab")
		)
		(fp_line
			(start 0.67945 -0.3048)
			(end 0.67945 0.3048)
			(stroke
				(width 0.1)
				(type default)
			)
			(layer "F.Fab")
		)
		(fp_line
			(start 0.12065 -0.3048)
			(end 0.67945 -0.3048)
			(stroke
				(width 0.1)
				(type default)
			)
			(layer "F.Fab")
		)
		(fp_line
			(start 0.12065 -0.2794)
			(end 0.12065 -0.3048)
			(stroke
				(width 0.1)
				(type default)
			)
			(layer "F.Fab")
		)
		(fp_line
			(start -0.12065 -0.2794)
			(end 0.12065 -0.2794)
			(stroke
				(width 0.1)
				(type default)
			)
			(layer "F.Fab")
		)
		(fp_line
			(start 0.120396 0.2794)
			(end -0.12065 0.2794)
			(stroke
				(width 0.1)
				(type default)
			)
			(layer "F.Fab")
		)
		(fp_line
			(start -0.12065 0.2794)
			(end -0.12065 0.3048)
			(stroke
				(width 0.1)
				(type default)
			)
			(layer "F.Fab")
		)
		(fp_line
			(start 0.67945 0.3048)
			(end 0.120396 0.3048)
			(stroke
				(width 0.1)
				(type default)
			)
			(layer "F.Fab")
		)
		(fp_line
			(start 0.120396 0.3048)
			(end 0.120396 0.2794)
			(stroke
				(width 0.1)
				(type default)
			)
			(layer "F.Fab")
		)
		(fp_line
			(start -0.12065 0.3048)
			(end -0.67945 0.3048)
			(stroke
				(width 0.1)
				(type default)
			)
			(layer "F.Fab")
		)
		(fp_line
			(start -0.67945 0.3048)
			(end -0.67945 -0.305054)
			(stroke
				(width 0.1)
				(type default)
			)
			(layer "F.Fab")
		)
		(pad "1" smd circle
			(at -0.40005 0 90)
			(size 0 0)
			(layers "F.Cu" "F.Mask" "F.Paste")
			(net "P0V62_CPU1_RST_DDR_VREF")
		)
		(pad "2" smd circle
			(at 0.40005 0 90)
			(size 0 0)
			(layers "F.Cu" "F.Mask" "F.Paste")
			(net "GND")
		)
	)
)
